# BASEBOARD_FAB2 (Tioga Pass) — schematic netlist excerpt (pin names and nets, part order shuffled) for the footprints in the layout excerpt that follows; sources: Cadence DE-HDL packaged netlist, KiCad conversion of Wiwynn_Tioga_Pass_MB.brd

R8F9  RES  49.9K 1% CHIP  pkg 0402  page 240 : A = VR_P3V3_STBY_OCSELECT ; B = AGND_P3V3_STBY

T1D2  TEST-PAD-12P-1-GP-U  pkg DISCRET-GB1  page 257
  DP  = L1_85OHM_5INCH_DN
  DN  = L1_85OHM_5INCH_DP
  GND(0)  = GND
  GND(1)  = GND
  GND(2)  = GND
  GND(3)  = GND
  GND(4)  = GND
  GND(5)  = GND
  GND(6)  = GND
  GND(7)  = GND
  GND(8)  = GND
  GND(9)  = GND

(kicad_pcb
	(version 20260206)
	(generator "pcbnew")
	(generator_version "10.0")
	(general
		(thickness 1.6)
		(legacy_teardrops no)
	)
	(paper "A4")
	(title_block
		(title "Wiwynn_Tioga_Pass_MB.brd")
		(comment 1 "Tioga Pass / footprints 1157-1158 of 4770")
	)
	(layers
		(0 "F.Cu" signal "TOP")
		(4 "In1.Cu" signal "L2GND")
		(6 "In2.Cu" signal "L3")
		(8 "In3.Cu" signal "L4GND")
		(10 "In4.Cu" signal "L5")
		(12 "In5.Cu" signal "L6GND")
		(14 "In6.Cu" signal "L7VCC")
		(16 "In7.Cu" signal "L8VCC")
		(18 "In8.Cu" signal "L9GND")
		(20 "In9.Cu" signal "L10")
		(22 "In10.Cu" signal "L11GND")
		(24 "In11.Cu" signal "L12")
		(26 "In12.Cu" signal "L13GND")
		(2 "B.Cu" signal "BOTTOM")
		(9 "F.Adhes" user "F.Adhesive")
		(11 "B.Adhes" user "B.Adhesive")
		(13 "F.Paste" user "Package Geometry/Pastemask Top")
		(15 "B.Paste" user "Package Geometry/Pastemask Bottom")
		(5 "F.SilkS" user "Ref Des/Silkscreen Top")
		(7 "B.SilkS" user "Ref Des/Silkscreen Bottom")
		(1 "F.Mask" user "Board Geometry/Soldermask Top")
		(3 "B.Mask" user "Board Geometry/Soldermask Bottom")
		(17 "Dwgs.User" user "User.Drawings")
		(19 "Cmts.User" user "User.Comments")
		(21 "Eco1.User" user "User.Eco1")
		(23 "Eco2.User" user "User.Eco2")
		(25 "Edge.Cuts" user "Board Geometry/Outline")
		(27 "Margin" user)
		(31 "F.CrtYd" user "Package Geometry/Place Bound Top")
		(29 "B.CrtYd" user "Package Geometry/Place Bound Bottom")
		(35 "F.Fab" user "Ref Des/Assembly Top")
		(33 "B.Fab" user "Ref Des/Assembly Bottom")
	)
	(footprint ""
		(layer "F.Cu")
		(at 466.5345 -20.6502 90)
		(property "Reference" "R8F9"
			(at 0 0 90)
			(layer "F.SilkS")
			(hide yes)
			(effects
				(font
					(size 1.27 1.27)
				)
			)
		)
		(property "Value" ""
			(at 0 0 90)
			(layer "F.Fab")
			(effects
				(font
					(size 1.27 1.27)
				)
			)
		)
		(duplicate_pad_numbers_are_jumpers no)
		(fp_rect
			(start -0.2794 -0.1016)
			(end 0.2794 0.9906)
			(stroke
				(width 0)
				(type default)
			)
			(fill no)
			(layer "F.CrtYd")
		)
		(fp_line
			(start 0.2794 -0.1016)
			(end -0.2794 -0.1016)
			(stroke
				(width 0.1)
				(type default)
			)
			(layer "F.Fab")
		)
		(fp_line
			(start -0.2794 -0.1016)
			(end -0.2794 0.9906)
			(stroke
				(width 0.1)
				(type default)
			)
			(layer "F.Fab")
		)
		(fp_line
			(start 0.2794 0.9906)
			(end 0.2794 -0.1016)
			(stroke
				(width 0.1)
				(type default)
			)
			(layer "F.Fab")
		)
		(fp_line
			(start -0.2794 0.9906)
			(end 0.2794 0.9906)
			(stroke
				(width 0.1)
				(type default)
			)
			(layer "F.Fab")
		)
		(pad "1" smd rect
			(at 0 0 90)
			(size 0.508 0.508)
			(layers "F.Cu" "F.Mask" "F.Paste")
			(net "VR_P3V3_STBY_OCSELECT")
		)
		(pad "2" smd rect
			(at 0 0.889 90)
			(size 0.508 0.508)
			(layers "F.Cu" "F.Mask" "F.Paste")
			(net "AGND_P3V3_STBY")
		)
		(zone
			(layer "F.Cu")
			(hatch none 0.5)
			(connect_pads
				(clearance 0)
			)
			(min_thickness 0.25)
			(keepout
				(tracks allowed)
				(vias not_allowed)
				(pads allowed)
				(copperpour not_allowed)
				(footprints allowed)
			)
			(placement
				(enabled no)
				(sheetname "")
			)
			(fill
				(thermal_gap 0.5)
				(thermal_bridge_width 0.5)
				(island_removal_mode 0)
			)
			(polygon
				(pts
					(xy 466.7885 -20.3962) (xy 467.1695 -20.3962) (xy 467.1695 -20.9042) (xy 466.7885 -20.9042)
				)
			)
		)
		(zone
			(layer "F.Cu")
			(hatch none 0.5)
			(connect_pads
				(clearance 0)
			)
			(min_thickness 0.25)
			(keepout
				(tracks not_allowed)
				(vias allowed)
				(pads allowed)
				(copperpour not_allowed)
				(footprints allowed)
			)
			(placement
				(enabled no)
				(sheetname "")
			)
			(fill
				(thermal_gap 0.5)
				(thermal_bridge_width 0.5)
				(island_removal_mode 0)
			)
			(polygon
				(pts
					(xy 466.7885 -20.3962) (xy 467.1695 -20.3962) (xy 467.1695 -20.9042) (xy 466.7885 -20.9042)
				)
			)
		)
	)
	(footprint ""
		(layer "F.Cu")
		(at 53.80228 -165.01618 90)
		(property "Reference" "T1D2"
			(at 0 0 90)
			(layer "F.SilkS")
			(hide yes)
			(effects
				(font
					(size 1.27 1.27)
				)
			)
		)
		(property "Value" "*"
			(at -3.4036 -4.46405 90)
			(unlocked yes)
			(layer "F.Fab")
			(hide yes)
			(effects
				(font
					(size 0.889 0.889)
					(thickness 0.1524)
				)
			)
		)
		(property "Device Type" "TEST-PAD-12P-1-GP-U_DISCRET-GBA"
			(at -3.4036 -5.98805 90)
			(unlocked yes)
			(layer "F.Fab")
			(hide yes)
			(effects
				(font
					(size 0.889 0.889)
					(thickness 0.1524)
				)
			)
		)
		(duplicate_pad_numbers_are_jumpers no)
		(fp_line
			(start 2.3622 -4.826)
			(end 2.3622 3.4798)
			(stroke
				(width 0.1524)
				(type default)
			)
			(layer "F.SilkS")
		)
		(fp_line
			(start -2.3876 -4.826)
			(end 2.3622 -4.826)
			(stroke
				(width 0.1524)
				(type default)
			)
			(layer "F.SilkS")
		)
		(fp_line
			(start 2.3622 3.4798)
			(end -2.3876 3.4798)
			(stroke
				(width 0.1524)
				(type default)
			)
			(layer "F.SilkS")
		)
		(fp_line
			(start -2.3876 3.4798)
			(end -2.3876 -4.826)
			(stroke
				(width 0.1524)
				(type default)
			)
			(layer "F.SilkS")
		)
		(fp_rect
			(start -2.6416 3.7338)
			(end 2.6162 -5.08)
			(stroke
				(width 0)
				(type default)
			)
			(fill no)
			(layer "F.CrtYd")
		)
		(fp_rect
			(start -2.6416 3.7338)
			(end 2.6162 -5.08)
			(stroke
				(width 0)
				(type default)
			)
			(fill no)
			(layer "F.Fab")
		)
		(pad "1" smd circle
			(at 0.496824 -1.301496 90)
			(size 0.6604 0.6604)
			(layers "F.Cu" "F.Mask" "F.Paste")
			(net "L1_85OHM_5INCH_DN")
		)
		(pad "2" smd circle
			(at -0.503936 -1.301496 90)
			(size 0.6604 0.6604)
			(layers "F.Cu" "F.Mask" "F.Paste")
			(net "L1_85OHM_5INCH_DP")
		)
		(pad "3" smd custom
			(at -0.00889 0.370078 90)
			(size 0.74295 0.74295)
			(layers "F.Cu" "F.Mask" "F.Paste")
			(net "GND")
			(options
				(clearance outline)
				(anchor circle)
			)
			(primitives
				(gr_poly
					(pts
						(xy -2.1209 1.4859) (xy 2.1209 1.4859) (xy 2.1209 -1.4859) (xy 1.08585 -1.4859) (xy 1.08585 -0.4699)
						(xy -1.08585 -0.4699) (xy -1.08585 -1.4859) (xy -2.1209 -1.4859)
					)
					(width 0)
					(fill yes)
				)
			)
		)
		(pad "4" thru_hole circle
			(at 1.266444 -3.851656 90)
			(size 1.4478 1.4478)
			(drill 1.0414)
			(layers "*.Cu" "*.Mask")
			(remove_unused_layers no)
			(net "GND")
			(clearance 0.1524)
			(thermal_gap 0.1524)
		)
		(pad "5" thru_hole circle
			(at -1.273556 -3.851656 90)
			(size 1.4478 1.4478)
			(drill 1.0414)
			(layers "*.Cu" "*.Mask")
			(remove_unused_layers no)
			(net "GND")
			(clearance 0.1524)
			(thermal_gap 0.1524)
		)
		(pad "6" thru_hole circle
			(at 1.266444 2.498344 90)
			(size 1.4478 1.4478)
			(drill 1.0414)
			(layers "*.Cu" "*.Mask")
			(remove_unused_layers no)
			(net "GND")
			(clearance 0.1524)
			(thermal_gap 0.1524)
		)
		(pad "7" thru_hole circle
			(at -1.273556 2.498344 90)
			(size 1.4478 1.4478)
			(drill 1.0414)
			(layers "*.Cu" "*.Mask")
			(remove_unused_layers no)
			(net "GND")
			(clearance 0.1524)
			(thermal_gap 0.1524)
		)
		(pad "8" thru_hole circle
			(at 1.27 -0.4572 90)
			(size 0.7112 0.7112)
			(drill 0.4064)
			(layers "*.Cu" "*.Mask")
			(remove_unused_layers no)
			(net "GND")
			(clearance 0.1016)
			(thermal_gap 0.1016)
		)
		(pad "9" thru_hole circle
			(at 1.27 0.762 90)
			(size 0.7112 0.7112)
			(drill 0.4064)
			(layers "*.Cu" "*.Mask")
			(remove_unused_layers no)
			(net "GND")
			(clearance 0.1016)
			(thermal_gap 0.1016)
		)
		(pad "10" thru_hole circle
			(at -0.0254 0.762 90)
			(size 0.7112 0.7112)
			(drill 0.4064)
			(layers "*.Cu" "*.Mask")
			(remove_unused_layers no)
			(net "GND")
			(clearance 0.1016)
			(thermal_gap 0.1016)
		)
		(pad "11" thru_hole circle
			(at -1.27 0.762 90)
			(size 0.7112 0.7112)
			(drill 0.4064)
			(layers "*.Cu" "*.Mask")
			(remove_unused_layers no)
			(net "GND")
			(clearance 0.1016)
			(thermal_gap 0.1016)
		)
		(pad "12" thru_hole circle
			(at -1.27 -0.4572 90)
			(size 0.7112 0.7112)
			(drill 0.4064)
			(layers "*.Cu" "*.Mask")
			(remove_unused_layers no)
			(net "GND")
			(clearance 0.1016)
			(thermal_gap 0.1016)
		)
	)
)
